# S9S_MB_2U (Grand Teton) — schematic netlist excerpt (pin names and nets, part order shuffled) for the footprints in the layout excerpt that follows; sources: Cadence DE-HDL packaged netlist, KiCad conversion of 03242023_DA0F0TMBIJ0_F0T_Motherboard_J_brd_V01_OCP.brd

R3206  Q_RES  0 5% EMPTY  pkg 0402LF  page 160 : A = FM_NCSI_OCP_V3_2_R_OE ; B = FB_BMC_ISOLATE1
R3532  Q_RES  4.7K 5% CHIP  pkg 0402LF  page 194 : A = P3V3_E1S_0 ; B = SMB_E1S_3V3AUX_ISO_SDA_R
PC1681  Q_CAP  22UF 16V 20% X6S  pkg C0805  page 290 : A = SW_P12V_PVCCFA_EHV_FIVRA_CPU1_R ; B = GND

(kicad_pcb
	(version 20260206)
	(generator "pcbnew")
	(generator_version "10.0")
	(general
		(thickness 1.6)
		(legacy_teardrops no)
	)
	(paper "A4")
	(title_block
		(title "03242023_DA0F0TMBIJ0_F0T_Motherboard_J_brd_V01_OCP.brd")
		(comment 1 "Grand Teton / footprints 779-781 of 6105")
	)
	(layers
		(0 "F.Cu" signal "TOP")
		(4 "In1.Cu" signal "GND")
		(6 "In2.Cu" signal "IN1")
		(8 "In3.Cu" signal "GND1")
		(10 "In4.Cu" signal "IN2")
		(12 "In5.Cu" signal "GND2")
		(14 "In6.Cu" signal "IN3")
		(16 "In7.Cu" signal "GND3")
		(18 "In8.Cu" signal "VCC")
		(20 "In9.Cu" signal "VCC1")
		(22 "In10.Cu" signal "GND4")
		(24 "In11.Cu" signal "IN4")
		(26 "In12.Cu" signal "GND5")
		(28 "In13.Cu" signal "IN5")
		(30 "In14.Cu" signal "GND6")
		(32 "In15.Cu" signal "IN6")
		(34 "In16.Cu" signal "GND7")
		(2 "B.Cu" signal "BOTTOM")
		(9 "F.Adhes" user "F.Adhesive")
		(11 "B.Adhes" user "B.Adhesive")
		(13 "F.Paste" user "Package Geometry/Pastemask Top")
		(15 "B.Paste" user "Package Geometry/Pastemask Bottom")
		(5 "F.SilkS" user "Ref Des/Silkscreen Top")
		(7 "B.SilkS" user "Ref Des/Silkscreen Bottom")
		(1 "F.Mask" user "Board Geometry/Soldermask Top")
		(3 "B.Mask" user "Board Geometry/Soldermask Bottom")
		(17 "Dwgs.User" user "User.Drawings")
		(19 "Cmts.User" user "User.Comments")
		(21 "Eco1.User" user "User.Eco1")
		(23 "Eco2.User" user "User.Eco2")
		(25 "Edge.Cuts" user "Board Geometry/Outline")
		(27 "Margin" user)
		(31 "F.CrtYd" user "Package Geometry/Place Bound Top")
		(29 "B.CrtYd" user "Package Geometry/Place Bound Bottom")
		(35 "F.Fab" user "Ref Des/Assembly Top")
		(33 "B.Fab" user "Ref Des/Assembly Bottom")
	)
	(footprint ""
		(layer "F.Cu")
		(at 152.96388 -129.758948 180)
		(property "Reference" "R3206"
			(at 0 0 180)
			(layer "F.SilkS")
			(hide yes)
			(effects
				(font
					(size 1.27 1.27)
				)
			)
		)
		(property "Value" ""
			(at 0 0 180)
			(layer "F.Fab")
			(effects
				(font
					(size 1.27 1.27)
				)
			)
		)
		(duplicate_pad_numbers_are_jumpers no)
		(fp_line
			(start 0.7874 0.4064)
			(end -0.7874 0.4064)
			(stroke
				(width 0.1524)
				(type default)
			)
			(layer "F.SilkS")
		)
		(fp_line
			(start 0.7874 -0.4064)
			(end 0.7874 0.4064)
			(stroke
				(width 0.1524)
				(type default)
			)
			(layer "F.SilkS")
		)
		(fp_line
			(start -0.7874 0.4064)
			(end -0.7874 -0.4064)
			(stroke
				(width 0.1524)
				(type default)
			)
			(layer "F.SilkS")
		)
		(fp_line
			(start -0.7874 -0.4064)
			(end 0.7874 -0.4064)
			(stroke
				(width 0.1524)
				(type default)
			)
			(layer "F.SilkS")
		)
		(fp_line
			(start 0.67945 0.3048)
			(end 0.120396 0.3048)
			(stroke
				(width 0.1)
				(type default)
			)
			(layer "F.Fab")
		)
		(fp_line
			(start 0.67945 -0.3048)
			(end 0.67945 0.3048)
			(stroke
				(width 0.1)
				(type default)
			)
			(layer "F.Fab")
		)
		(fp_line
			(start 0.12065 -0.2794)
			(end 0.12065 -0.3048)
			(stroke
				(width 0.1)
				(type default)
			)
			(layer "F.Fab")
		)
		(fp_line
			(start 0.12065 -0.3048)
			(end 0.67945 -0.3048)
			(stroke
				(width 0.1)
				(type default)
			)
			(layer "F.Fab")
		)
		(fp_line
			(start 0.120396 0.3048)
			(end 0.120396 0.2794)
			(stroke
				(width 0.1)
				(type default)
			)
			(layer "F.Fab")
		)
		(fp_line
			(start 0.120396 0.2794)
			(end -0.12065 0.2794)
			(stroke
				(width 0.1)
				(type default)
			)
			(layer "F.Fab")
		)
		(fp_line
			(start -0.12065 0.3048)
			(end -0.67945 0.3048)
			(stroke
				(width 0.1)
				(type default)
			)
			(layer "F.Fab")
		)
		(fp_line
			(start -0.12065 0.2794)
			(end -0.12065 0.3048)
			(stroke
				(width 0.1)
				(type default)
			)
			(layer "F.Fab")
		)
		(fp_line
			(start -0.12065 -0.2794)
			(end 0.12065 -0.2794)
			(stroke
				(width 0.1)
				(type default)
			)
			(layer "F.Fab")
		)
		(fp_line
			(start -0.12065 -0.305054)
			(end -0.12065 -0.2794)
			(stroke
				(width 0.1)
				(type default)
			)
			(layer "F.Fab")
		)
		(fp_line
			(start -0.67945 0.3048)
			(end -0.67945 -0.305054)
			(stroke
				(width 0.1)
				(type default)
			)
			(layer "F.Fab")
		)
		(fp_line
			(start -0.67945 -0.305054)
			(end -0.12065 -0.305054)
			(stroke
				(width 0.1)
				(type default)
			)
			(layer "F.Fab")
		)
		(pad "1" smd circle
			(at -0.40005 0 180)
			(size 0 0)
			(layers "F.Cu" "F.Mask" "F.Paste")
			(net "FM_NCSI_OCP_V3_2_R_OE")
		)
		(pad "2" smd circle
			(at 0.40005 0 180)
			(size 0 0)
			(layers "F.Cu" "F.Mask" "F.Paste")
			(net "FB_BMC_ISOLATE1")
		)
	)
	(footprint ""
		(layer "F.Cu")
		(at 187.28944 -355.90607)
		(property "Reference" "PC1681"
			(at 0 0 0)
			(layer "F.SilkS")
			(hide yes)
			(effects
				(font
					(size 1.27 1.27)
				)
			)
		)
		(property "Value" ""
			(at 0 0 0)
			(layer "F.Fab")
			(effects
				(font
					(size 1.27 1.27)
				)
			)
		)
		(duplicate_pad_numbers_are_jumpers no)
		(fp_line
			(start -1.524 -0.762)
			(end 1.524 -0.762)
			(stroke
				(width 0.1524)
				(type default)
			)
			(layer "F.SilkS")
		)
		(fp_line
			(start -1.524 0.762)
			(end -1.524 -0.762)
			(stroke
				(width 0.1524)
				(type default)
			)
			(layer "F.SilkS")
		)
		(fp_line
			(start 1.524 -0.762)
			(end 1.524 0.762)
			(stroke
				(width 0.1524)
				(type default)
			)
			(layer "F.SilkS")
		)
		(fp_line
			(start 1.524 0.762)
			(end -1.524 0.762)
			(stroke
				(width 0.1524)
				(type default)
			)
			(layer "F.SilkS")
		)
		(fp_line
			(start -1.1049 -0.724916)
			(end -1.1049 0.724916)
			(stroke
				(width 0.1)
				(type default)
			)
			(layer "F.Fab")
		)
		(fp_line
			(start -1.1049 0.724916)
			(end 1.1049 0.724916)
			(stroke
				(width 0.1)
				(type default)
			)
			(layer "F.Fab")
		)
		(fp_line
			(start 1.1049 -0.724916)
			(end -1.1049 -0.724916)
			(stroke
				(width 0.1)
				(type default)
			)
			(layer "F.Fab")
		)
		(fp_line
			(start 1.1049 0.724916)
			(end 1.1049 -0.724916)
			(stroke
				(width 0.1)
				(type default)
			)
			(layer "F.Fab")
		)
		(pad "1" smd rect
			(at -0.889 0 180)
			(size 1.016 1.27)
			(layers "F.Cu" "F.Mask" "F.Paste")
			(net "SW_P12V_PVCCFA_EHV_FIVRA_CPU1_R")
		)
		(pad "2" smd rect
			(at 0.889 0 180)
			(size 1.016 1.27)
			(layers "F.Cu" "F.Mask" "F.Paste")
			(net "GND")
		)
	)
	(footprint ""
		(layer "F.Cu")
		(at 221.67088 -44.922948 180)
		(property "Reference" "R3532"
			(at 0 0 180)
			(layer "F.SilkS")
			(hide yes)
			(effects
				(font
					(size 1.27 1.27)
				)
			)
		)
		(property "Value" ""
			(at 0 0 180)
			(layer "F.Fab")
			(effects
				(font
					(size 1.27 1.27)
				)
			)
		)
		(duplicate_pad_numbers_are_jumpers no)
		(fp_line
			(start 0.7874 0.4064)
			(end -0.7874 0.4064)
			(stroke
				(width 0.1524)
				(type default)
			)
			(layer "F.SilkS")
		)
		(fp_line
			(start 0.7874 -0.4064)
			(end 0.7874 0.4064)
			(stroke
				(width 0.1524)
				(type default)
			)
			(layer "F.SilkS")
		)
		(fp_line
			(start -0.7874 0.4064)
			(end -0.7874 -0.4064)
			(stroke
				(width 0.1524)
				(type default)
			)
			(layer "F.SilkS")
		)
		(fp_line
			(start -0.7874 -0.4064)
			(end 0.7874 -0.4064)
			(stroke
				(width 0.1524)
				(type default)
			)
			(layer "F.SilkS")
		)
		(fp_line
			(start 0.67945 0.3048)
			(end 0.120396 0.3048)
			(stroke
				(width 0.1)
				(type default)
			)
			(layer "F.Fab")
		)
		(fp_line
			(start 0.67945 -0.3048)
			(end 0.67945 0.3048)
			(stroke
				(width 0.1)
				(type default)
			)
			(layer "F.Fab")
		)
		(fp_line
			(start 0.12065 -0.2794)
			(end 0.12065 -0.3048)
			(stroke
				(width 0.1)
				(type default)
			)
			(layer "F.Fab")
		)
		(fp_line
			(start 0.12065 -0.3048)
			(end 0.67945 -0.3048)
			(stroke
				(width 0.1)
				(type default)
			)
			(layer "F.Fab")
		)
		(fp_line
			(start 0.120396 0.3048)
			(end 0.120396 0.2794)
			(stroke
				(width 0.1)
				(type default)
			)
			(layer "F.Fab")
		)
		(fp_line
			(start 0.120396 0.2794)
			(end -0.12065 0.2794)
			(stroke
				(width 0.1)
				(type default)
			)
			(layer "F.Fab")
		)
		(fp_line
			(start -0.12065 0.3048)
			(end -0.67945 0.3048)
			(stroke
				(width 0.1)
				(type default)
			)
			(layer "F.Fab")
		)
		(fp_line
			(start -0.12065 0.2794)
			(end -0.12065 0.3048)
			(stroke
				(width 0.1)
				(type default)
			)
			(layer "F.Fab")
		)
		(fp_line
			(start -0.12065 -0.2794)
			(end 0.12065 -0.2794)
			(stroke
				(width 0.1)
				(type default)
			)
			(layer "F.Fab")
		)
		(fp_line
			(start -0.12065 -0.305054)
			(end -0.12065 -0.2794)
			(stroke
				(width 0.1)
				(type default)
			)
			(layer "F.Fab")
		)
		(fp_line
			(start -0.67945 0.3048)
			(end -0.67945 -0.305054)
			(stroke
				(width 0.1)
				(type default)
			)
			(layer "F.Fab")
		)
		(fp_line
			(start -0.67945 -0.305054)
			(end -0.12065 -0.305054)
			(stroke
				(width 0.1)
				(type default)
			)
			(layer "F.Fab")
		)
		(pad "1" smd circle
			(at -0.40005 0 180)
			(size 0 0)
			(layers "F.Cu" "F.Mask" "F.Paste")
			(net "P3V3_E1S_0")
		)
		(pad "2" smd circle
			(at 0.40005 0 180)
			(size 0 0)
			(layers "F.Cu" "F.Mask" "F.Paste")
			(net "SMB_E1S_3V3AUX_ISO_SDA_R")
		)
	)
)
